(kicad_pcb
	(version 20260206)
	(generator "pcbnew")
	(generator_version "10.0")
	(general
		(thickness 1.6)
		(legacy_teardrops no)
	)
	(paper "A4")
	(title_block
		(title "04192023_DAF0TMB3IC0_F0TG_MB_C_brd_V02_OCP.brd")
		(comment 1 "Grand Teton / footprints 6777-6783 of 8354")
	)
	(layers
		(0 "F.Cu" signal "TOP")
		(4 "In1.Cu" signal "GND")
		(6 "In2.Cu" signal "IN1")
		(8 "In3.Cu" signal "GND1")
		(10 "In4.Cu" signal "IN2")
		(12 "In5.Cu" signal "GND2")
		(14 "In6.Cu" signal "IN3")
		(16 "In7.Cu" signal "GND3")
		(18 "In8.Cu" signal "VCC")
		(20 "In9.Cu" signal "VCC1")
		(22 "In10.Cu" signal "GND4")
		(24 "In11.Cu" signal "IN4")
		(26 "In12.Cu" signal "GND5")
		(28 "In13.Cu" signal "IN5")
		(30 "In14.Cu" signal "GND6")
		(32 "In15.Cu" signal "IN6")
		(34 "In16.Cu" signal "GND7")
		(2 "B.Cu" signal "BOTTOM")
		(9 "F.Adhes" user "F.Adhesive")
		(11 "B.Adhes" user "B.Adhesive")
		(13 "F.Paste" user "Package Geometry/Pastemask Top")
		(15 "B.Paste" user "Package Geometry/Pastemask Bottom")
		(5 "F.SilkS" user "Ref Des/Silkscreen Top")
		(7 "B.SilkS" user "Ref Des/Silkscreen Bottom")
		(1 "F.Mask" user "Board Geometry/Soldermask Top")
		(3 "B.Mask" user "Board Geometry/Soldermask Bottom")
		(17 "Dwgs.User" user "User.Drawings")
		(19 "Cmts.User" user "User.Comments")
		(21 "Eco1.User" user "User.Eco1")
		(23 "Eco2.User" user "User.Eco2")
		(25 "Edge.Cuts" user "Board Geometry/Outline")
		(27 "Margin" user)
		(31 "F.CrtYd" user "Package Geometry/Place Bound Top")
		(29 "B.CrtYd" user "Package Geometry/Place Bound Bottom")
		(35 "F.Fab" user "Ref Des/Assembly Top")
		(33 "B.Fab" user "Ref Des/Assembly Bottom")
	)
	(footprint ""
		(layer "B.Cu")
		(at 189.087506 -126.833376 -90)
		(property "Reference" "R1550"
			(at 0 0 90)
			(layer "B.SilkS")
			(hide yes)
			(effects
				(font
					(size 1.27 1.27)
				)
				(justify mirror)
			)
		)
		(property "Value" ""
			(at 0 0 90)
			(layer "B.Fab")
			(effects
				(font
					(size 1.27 1.27)
				)
				(justify mirror)
			)
		)
		(duplicate_pad_numbers_are_jumpers no)
		(fp_line
			(start -0.7874 0.4064)
			(end 0.7874 0.4064)
			(stroke
				(width 0.1524)
				(type default)
			)
			(layer "B.SilkS")
		)
		(fp_line
			(start 0.7874 0.4064)
			(end 0.7874 -0.4064)
			(stroke
				(width 0.1524)
				(type default)
			)
			(layer "B.SilkS")
		)
		(fp_line
			(start -0.7874 -0.4064)
			(end -0.7874 0.4064)
			(stroke
				(width 0.1524)
				(type default)
			)
			(layer "B.SilkS")
		)
		(fp_line
			(start 0.7874 -0.4064)
			(end -0.7874 -0.4064)
			(stroke
				(width 0.1524)
				(type default)
			)
			(layer "B.SilkS")
		)
		(fp_line
			(start -0.67945 0.3048)
			(end -0.120396 0.3048)
			(stroke
				(width 0.1)
				(type default)
			)
			(layer "B.Fab")
		)
		(fp_line
			(start -0.120396 0.3048)
			(end -0.120396 0.2794)
			(stroke
				(width 0.1)
				(type default)
			)
			(layer "B.Fab")
		)
		(fp_line
			(start 0.12065 0.3048)
			(end 0.67945 0.3048)
			(stroke
				(width 0.1)
				(type default)
			)
			(layer "B.Fab")
		)
		(fp_line
			(start 0.67945 0.3048)
			(end 0.67945 -0.305054)
			(stroke
				(width 0.1)
				(type default)
			)
			(layer "B.Fab")
		)
		(fp_line
			(start -0.120396 0.2794)
			(end 0.12065 0.2794)
			(stroke
				(width 0.1)
				(type default)
			)
			(layer "B.Fab")
		)
		(fp_line
			(start 0.12065 0.2794)
			(end 0.12065 0.3048)
			(stroke
				(width 0.1)
				(type default)
			)
			(layer "B.Fab")
		)
		(fp_line
			(start -0.12065 -0.2794)
			(end -0.12065 -0.3048)
			(stroke
				(width 0.1)
				(type default)
			)
			(layer "B.Fab")
		)
		(fp_line
			(start 0.12065 -0.2794)
			(end -0.12065 -0.2794)
			(stroke
				(width 0.1)
				(type default)
			)
			(layer "B.Fab")
		)
		(fp_line
			(start -0.67945 -0.3048)
			(end -0.67945 0.3048)
			(stroke
				(width 0.1)
				(type default)
			)
			(layer "B.Fab")
		)
		(fp_line
			(start -0.12065 -0.3048)
			(end -0.67945 -0.3048)
			(stroke
				(width 0.1)
				(type default)
			)
			(layer "B.Fab")
		)
		(fp_line
			(start 0.12065 -0.305054)
			(end 0.12065 -0.2794)
			(stroke
				(width 0.1)
				(type default)
			)
			(layer "B.Fab")
		)
		(fp_line
			(start 0.67945 -0.305054)
			(end 0.12065 -0.305054)
			(stroke
				(width 0.1)
				(type default)
			)
			(layer "B.Fab")
		)
		(pad "1" smd circle
			(at 0.40005 0 90)
			(size 0 0)
			(layers "B.Cu" "B.Mask" "B.Paste")
			(net "ESPI_CPU0_R1_D1")
		)
		(pad "2" smd circle
			(at -0.40005 0 90)
			(size 0 0)
			(layers "B.Cu" "B.Mask" "B.Paste")
			(net "ESPI_CPU0_D1")
		)
	)
	(footprint ""
		(layer "B.Cu")
		(at 446.579752 -390.405874 -90)
		(property "Reference" "PC6811"
			(at -0.754126 2.995422 270)
			(unlocked yes)
			(layer "B.SilkS")
			(effects
				(font
					(size 0.7874 0.5842)
					(thickness 0.1524)
				)
				(justify left mirror)
			)
		)
		(property "Value" ""
			(at 0 0 90)
			(layer "B.Fab")
			(effects
				(font
					(size 1.27 1.27)
				)
				(justify mirror)
			)
		)
		(duplicate_pad_numbers_are_jumpers no)
		(fp_line
			(start 4.83108 2.150364)
			(end 4.447794 2.149348)
			(stroke
				(width 0.1524)
				(type default)
			)
			(layer "B.SilkS")
		)
		(fp_line
			(start -4.53898 2.15011)
			(end 4.53898 2.15011)
			(stroke
				(width 0.1524)
				(type default)
			)
			(layer "B.SilkS")
		)
		(fp_line
			(start 4.53898 2.15011)
			(end 4.53898 -2.15011)
			(stroke
				(width 0.1524)
				(type default)
			)
			(layer "B.SilkS")
		)
		(fp_line
			(start -4.53898 -2.15011)
			(end -4.53898 2.15011)
			(stroke
				(width 0.1524)
				(type default)
			)
			(layer "B.SilkS")
		)
		(fp_line
			(start 4.53898 -2.15011)
			(end -4.53898 -2.15011)
			(stroke
				(width 0.1524)
				(type default)
			)
			(layer "B.SilkS")
		)
		(fp_line
			(start 4.53898 -2.150618)
			(end 4.539742 2.152142)
			(stroke
				(width 0.1524)
				(type default)
			)
			(layer "B.SilkS")
		)
		(fp_line
			(start 4.69138 -2.150618)
			(end 4.692396 2.161032)
			(stroke
				(width 0.1524)
				(type default)
			)
			(layer "B.SilkS")
		)
		(fp_line
			(start 4.84378 -2.150618)
			(end 4.842256 2.163064)
			(stroke
				(width 0.1524)
				(type default)
			)
			(layer "B.SilkS")
		)
		(fp_line
			(start 4.84378 -2.150618)
			(end 4.53898 -2.150618)
			(stroke
				(width 0.1524)
				(type default)
			)
			(layer "B.SilkS")
		)
		(fp_line
			(start -3.64998 2.15011)
			(end 3.64998 2.15011)
			(stroke
				(width 0.1)
				(type default)
			)
			(layer "B.Fab")
		)
		(fp_line
			(start 3.64998 2.15011)
			(end 3.64998 -2.15011)
			(stroke
				(width 0.1)
				(type default)
			)
			(layer "B.Fab")
		)
		(fp_line
			(start -3.64998 -2.15011)
			(end -3.64998 2.15011)
			(stroke
				(width 0.1)
				(type default)
			)
			(layer "B.Fab")
		)
		(fp_line
			(start 3.64998 -2.15011)
			(end -3.64998 -2.15011)
			(stroke
				(width 0.1)
				(type default)
			)
			(layer "B.Fab")
		)
		(fp_text user "+"
			(at 6.329172 -0.680212 270)
			(unlocked yes)
			(layer "B.SilkS")
			(effects
				(font
					(size 1.905 1.4224)
					(thickness 0.1524)
				)
				(justify left mirror)
			)
		)
		(fp_text user "-"
			(at -4.731512 -3.37566 270)
			(unlocked yes)
			(layer "B.SilkS")
			(effects
				(font
					(size 1.905 1.4224)
					(thickness 0.1524)
				)
				(justify left mirror)
			)
		)
		(fp_text user "-"
			(at -4.313174 -0.094488 270)
			(unlocked yes)
			(layer "B.Fab")
			(effects
				(font
					(size 1.905 1.4224)
					(thickness 0.1524)
				)
				(justify left mirror)
			)
		)
		(fp_text user "+"
			(at 6.214872 -0.337058 270)
			(unlocked yes)
			(layer "B.Fab")
			(effects
				(font
					(size 1.905 1.4224)
					(thickness 0.1524)
				)
				(justify left mirror)
			)
		)
		(pad "1" smd rect
			(at 3.199892 0 90)
			(size 2.413 2.8194)
			(layers "B.Cu" "B.Mask" "B.Paste")
			(net "P0V9_CPU0_RT_2D")
		)
		(pad "2" smd rect
			(at -3.199892 0 90)
			(size 2.413 2.8194)
			(layers "B.Cu" "B.Mask" "B.Paste")
			(net "GND")
		)
	)
	(footprint ""
		(layer "B.Cu")
		(at 175.50638 -422.234614 180)
		(property "Reference" "R6238"
			(at 0 0 0)
			(layer "B.SilkS")
			(hide yes)
			(effects
				(font
					(size 1.27 1.27)
				)
				(justify mirror)
			)
		)
		(property "Value" ""
			(at 0 0 0)
			(layer "B.Fab")
			(effects
				(font
					(size 1.27 1.27)
				)
				(justify mirror)
			)
		)
		(duplicate_pad_numbers_are_jumpers no)
		(fp_line
			(start 0.7874 0.4064)
			(end 0.7874 -0.4064)
			(stroke
				(width 0.1524)
				(type default)
			)
			(layer "B.SilkS")
		)
		(fp_line
			(start 0.7874 -0.4064)
			(end -0.7874 -0.4064)
			(stroke
				(width 0.1524)
				(type default)
			)
			(layer "B.SilkS")
		)
		(fp_line
			(start -0.7874 0.4064)
			(end 0.7874 0.4064)
			(stroke
				(width 0.1524)
				(type default)
			)
			(layer "B.SilkS")
		)
		(fp_line
			(start -0.7874 -0.4064)
			(end -0.7874 0.4064)
			(stroke
				(width 0.1524)
				(type default)
			)
			(layer "B.SilkS")
		)
		(fp_line
			(start 0.67945 0.3048)
			(end 0.67945 -0.305054)
			(stroke
				(width 0.1)
				(type default)
			)
			(layer "B.Fab")
		)
		(fp_line
			(start 0.67945 -0.305054)
			(end 0.12065 -0.305054)
			(stroke
				(width 0.1)
				(type default)
			)
			(layer "B.Fab")
		)
		(fp_line
			(start 0.12065 0.3048)
			(end 0.67945 0.3048)
			(stroke
				(width 0.1)
				(type default)
			)
			(layer "B.Fab")
		)
		(fp_line
			(start 0.12065 0.2794)
			(end 0.12065 0.3048)
			(stroke
				(width 0.1)
				(type default)
			)
			(layer "B.Fab")
		)
		(fp_line
			(start 0.12065 -0.2794)
			(end -0.12065 -0.2794)
			(stroke
				(width 0.1)
				(type default)
			)
			(layer "B.Fab")
		)
		(fp_line
			(start 0.12065 -0.305054)
			(end 0.12065 -0.2794)
			(stroke
				(width 0.1)
				(type default)
			)
			(layer "B.Fab")
		)
		(fp_line
			(start -0.120396 0.3048)
			(end -0.120396 0.2794)
			(stroke
				(width 0.1)
				(type default)
			)
			(layer "B.Fab")
		)
		(fp_line
			(start -0.120396 0.2794)
			(end 0.12065 0.2794)
			(stroke
				(width 0.1)
				(type default)
			)
			(layer "B.Fab")
		)
		(fp_line
			(start -0.12065 -0.2794)
			(end -0.12065 -0.3048)
			(stroke
				(width 0.1)
				(type default)
			)
			(layer "B.Fab")
		)
		(fp_line
			(start -0.12065 -0.3048)
			(end -0.67945 -0.3048)
			(stroke
				(width 0.1)
				(type default)
			)
			(layer "B.Fab")
		)
		(fp_line
			(start -0.67945 0.3048)
			(end -0.120396 0.3048)
			(stroke
				(width 0.1)
				(type default)
			)
			(layer "B.Fab")
		)
		(fp_line
			(start -0.67945 -0.3048)
			(end -0.67945 0.3048)
			(stroke
				(width 0.1)
				(type default)
			)
			(layer "B.Fab")
		)
		(pad "1" smd circle
			(at 0.40005 0)
			(size 0 0)
			(layers "B.Cu" "B.Mask" "B.Paste")
			(net "A_HSC_LOW_DRAIN")
		)
		(pad "2" smd circle
			(at -0.40005 0)
			(size 0 0)
			(layers "B.Cu" "B.Mask" "B.Paste")
			(net "HSC_D_OC")
		)
	)
	(footprint ""
		(layer "B.Cu")
		(at 116.891308 -390.560052 90)
		(property "Reference" "C472"
			(at 0 0 90)
			(layer "B.SilkS")
			(hide yes)
			(effects
				(font
					(size 1.27 1.27)
				)
				(justify mirror)
			)
		)
		(property "Value" ""
			(at 0 0 90)
			(layer "B.Fab")
			(effects
				(font
					(size 1.27 1.27)
				)
				(justify mirror)
			)
		)
		(duplicate_pad_numbers_are_jumpers no)
		(fp_line
			(start 0.7874 -0.4064)
			(end -0.7874 -0.4064)
			(stroke
				(width 0.1524)
				(type default)
			)
			(layer "B.SilkS")
		)
		(fp_line
			(start -0.7874 -0.4064)
			(end -0.7874 0.4064)
			(stroke
				(width 0.1524)
				(type default)
			)
			(layer "B.SilkS")
		)
		(fp_line
			(start 0.7874 0.4064)
			(end 0.7874 -0.4064)
			(stroke
				(width 0.1524)
				(type default)
			)
			(layer "B.SilkS")
		)
		(fp_line
			(start -0.7874 0.4064)
			(end 0.7874 0.4064)
			(stroke
				(width 0.1524)
				(type default)
			)
			(layer "B.SilkS")
		)
		(fp_line
			(start 0.67945 -0.305054)
			(end 0.12065 -0.305054)
			(stroke
				(width 0.1)
				(type default)
			)
			(layer "B.Fab")
		)
		(fp_line
			(start 0.12065 -0.305054)
			(end 0.12065 -0.2794)
			(stroke
				(width 0.1)
				(type default)
			)
			(layer "B.Fab")
		)
		(fp_line
			(start -0.12065 -0.3048)
			(end -0.67945 -0.3048)
			(stroke
				(width 0.1)
				(type default)
			)
			(layer "B.Fab")
		)
		(fp_line
			(start -0.67945 -0.3048)
			(end -0.67945 0.3048)
			(stroke
				(width 0.1)
				(type default)
			)
			(layer "B.Fab")
		)
		(fp_line
			(start 0.12065 -0.2794)
			(end -0.12065 -0.2794)
			(stroke
				(width 0.1)
				(type default)
			)
			(layer "B.Fab")
		)
		(fp_line
			(start -0.12065 -0.2794)
			(end -0.12065 -0.3048)
			(stroke
				(width 0.1)
				(type default)
			)
			(layer "B.Fab")
		)
		(fp_line
			(start 0.12065 0.2794)
			(end 0.12065 0.3048)
			(stroke
				(width 0.1)
				(type default)
			)
			(layer "B.Fab")
		)
		(fp_line
			(start -0.120396 0.2794)
			(end 0.12065 0.2794)
			(stroke
				(width 0.1)
				(type default)
			)
			(layer "B.Fab")
		)
		(fp_line
			(start 0.67945 0.3048)
			(end 0.67945 -0.305054)
			(stroke
				(width 0.1)
				(type default)
			)
			(layer "B.Fab")
		)
		(fp_line
			(start 0.12065 0.3048)
			(end 0.67945 0.3048)
			(stroke
				(width 0.1)
				(type default)
			)
			(layer "B.Fab")
		)
		(fp_line
			(start -0.120396 0.3048)
			(end -0.120396 0.2794)
			(stroke
				(width 0.1)
				(type default)
			)
			(layer "B.Fab")
		)
		(fp_line
			(start -0.67945 0.3048)
			(end -0.120396 0.3048)
			(stroke
				(width 0.1)
				(type default)
			)
			(layer "B.Fab")
		)
		(pad "1" smd circle
			(at 0.40005 0 270)
			(size 0 0)
			(layers "B.Cu" "B.Mask" "B.Paste")
			(net "P0V9_CPU1_RT3_2A")
		)
		(pad "2" smd circle
			(at -0.40005 0 270)
			(size 0 0)
			(layers "B.Cu" "B.Mask" "B.Paste")
			(net "GND")
		)
	)
	(footprint ""
		(layer "B.Cu")
		(at 398.249902 -152.29078 -90)
		(property "Reference" "R4638"
			(at 0 0 90)
			(layer "B.SilkS")
			(hide yes)
			(effects
				(font
					(size 1.27 1.27)
				)
				(justify mirror)
			)
		)
		(property "Value" ""
			(at 0 0 90)
			(layer "B.Fab")
			(effects
				(font
					(size 1.27 1.27)
				)
				(justify mirror)
			)
		)
		(duplicate_pad_numbers_are_jumpers no)
		(fp_line
			(start -2.234946 0.9271)
			(end 2.234946 0.9271)
			(stroke
				(width 0.1524)
				(type default)
			)
			(layer "B.SilkS")
		)
		(fp_line
			(start 2.234946 0.9271)
			(end 2.234946 -0.9271)
			(stroke
				(width 0.1524)
				(type default)
			)
			(layer "B.SilkS")
		)
		(fp_line
			(start -2.234946 -0.9271)
			(end -2.234946 0.9271)
			(stroke
				(width 0.1524)
				(type default)
			)
			(layer "B.SilkS")
		)
		(fp_line
			(start 2.234946 -0.9271)
			(end -2.234946 -0.9271)
			(stroke
				(width 0.1524)
				(type default)
			)
			(layer "B.SilkS")
		)
		(fp_line
			(start -1.575054 0.824992)
			(end -1.575054 -0.824992)
			(stroke
				(width 0.1)
				(type default)
			)
			(layer "B.Fab")
		)
		(fp_line
			(start 1.575054 0.824992)
			(end -1.575054 0.824992)
			(stroke
				(width 0.1)
				(type default)
			)
			(layer "B.Fab")
		)
		(fp_line
			(start -1.575054 -0.824992)
			(end 1.575054 -0.824992)
			(stroke
				(width 0.1)
				(type default)
			)
			(layer "B.Fab")
		)
		(fp_line
			(start 1.575054 -0.824992)
			(end 1.575054 0.824992)
			(stroke
				(width 0.1)
				(type default)
			)
			(layer "B.Fab")
		)
		(pad "1" smd rect
			(at 1.599946 0 90)
			(size 1.016 1.6002)
			(layers "B.Cu" "B.Mask" "B.Paste")
			(net "P5V")
		)
		(pad "2" smd rect
			(at -1.599946 0 90)
			(size 1.016 1.6002)
			(layers "B.Cu" "B.Mask" "B.Paste")
			(net "VR_P5V_EN_D")
		)
	)
	(footprint ""
		(layer "B.Cu")
		(at 76.20508 -11.267948 90)
		(property "Reference" "R3173"
			(at 0 0 90)
			(layer "B.SilkS")
			(hide yes)
			(effects
				(font
					(size 1.27 1.27)
				)
				(justify mirror)
			)
		)
		(property "Value" ""
			(at 0 0 90)
			(layer "B.Fab")
			(effects
				(font
					(size 1.27 1.27)
				)
				(justify mirror)
			)
		)
		(duplicate_pad_numbers_are_jumpers no)
		(fp_line
			(start 0.7874 -0.4064)
			(end -0.7874 -0.4064)
			(stroke
				(width 0.1524)
				(type default)
			)
			(layer "B.SilkS")
		)
		(fp_line
			(start -0.7874 -0.4064)
			(end -0.7874 0.4064)
			(stroke
				(width 0.1524)
				(type default)
			)
			(layer "B.SilkS")
		)
		(fp_line
			(start 0.7874 0.4064)
			(end 0.7874 -0.4064)
			(stroke
				(width 0.1524)
				(type default)
			)
			(layer "B.SilkS")
		)
		(fp_line
			(start -0.7874 0.4064)
			(end 0.7874 0.4064)
			(stroke
				(width 0.1524)
				(type default)
			)
			(layer "B.SilkS")
		)
		(fp_line
			(start 0.67945 -0.305054)
			(end 0.12065 -0.305054)
			(stroke
				(width 0.1)
				(type default)
			)
			(layer "B.Fab")
		)
		(fp_line
			(start 0.12065 -0.305054)
			(end 0.12065 -0.2794)
			(stroke
				(width 0.1)
				(type default)
			)
			(layer "B.Fab")
		)
		(fp_line
			(start -0.12065 -0.3048)
			(end -0.67945 -0.3048)
			(stroke
				(width 0.1)
				(type default)
			)
			(layer "B.Fab")
		)
		(fp_line
			(start -0.67945 -0.3048)
			(end -0.67945 0.3048)
			(stroke
				(width 0.1)
				(type default)
			)
			(layer "B.Fab")
		)
		(fp_line
			(start 0.12065 -0.2794)
			(end -0.12065 -0.2794)
			(stroke
				(width 0.1)
				(type default)
			)
			(layer "B.Fab")
		)
		(fp_line
			(start -0.12065 -0.2794)
			(end -0.12065 -0.3048)
			(stroke
				(width 0.1)
				(type default)
			)
			(layer "B.Fab")
		)
		(fp_line
			(start 0.12065 0.2794)
			(end 0.12065 0.3048)
			(stroke
				(width 0.1)
				(type default)
			)
			(layer "B.Fab")
		)
		(fp_line
			(start -0.120396 0.2794)
			(end 0.12065 0.2794)
			(stroke
				(width 0.1)
				(type default)
			)
			(layer "B.Fab")
		)
		(fp_line
			(start 0.67945 0.3048)
			(end 0.67945 -0.305054)
			(stroke
				(width 0.1)
				(type default)
			)
			(layer "B.Fab")
		)
		(fp_line
			(start 0.12065 0.3048)
			(end 0.67945 0.3048)
			(stroke
				(width 0.1)
				(type default)
			)
			(layer "B.Fab")
		)
		(fp_line
			(start -0.120396 0.3048)
			(end -0.120396 0.2794)
			(stroke
				(width 0.1)
				(type default)
			)
			(layer "B.Fab")
		)
		(fp_line
			(start -0.67945 0.3048)
			(end -0.120396 0.3048)
			(stroke
				(width 0.1)
				(type default)
			)
			(layer "B.Fab")
		)
		(pad "1" smd circle
			(at 0.40005 0 270)
			(size 0 0)
			(layers "B.Cu" "B.Mask" "B.Paste")
			(net "SGPIO_OCP_V3_2_LD_N")
		)
		(pad "2" smd circle
			(at -0.40005 0 270)
			(size 0 0)
			(layers "B.Cu" "B.Mask" "B.Paste")
			(net "P3V3_OCP_V3_2")
		)
	)
	(footprint ""
		(layer "B.Cu")
		(at 368.51844 -395.43228)
		(property "Reference" "C1050"
			(at 0 0 0)
			(layer "B.SilkS")
			(hide yes)
			(effects
				(font
					(size 1.27 1.27)
				)
				(justify mirror)
			)
		)
		(property "Value" ""
			(at 0 0 0)
			(layer "B.Fab")
			(effects
				(font
					(size 1.27 1.27)
				)
				(justify mirror)
			)
		)
		(duplicate_pad_numbers_are_jumpers no)
		(fp_line
			(start -0.299974 -0.150114)
			(end -0.299974 0.150114)
			(stroke
				(width 0.1)
				(type default)
			)
			(layer "B.Fab")
		)
		(fp_line
			(start -0.299974 0.150114)
			(end 0.299974 0.150114)
			(stroke
				(width 0.1)
				(type default)
			)
			(layer "B.Fab")
		)
		(fp_line
			(start 0.299974 -0.150114)
			(end -0.299974 -0.150114)
			(stroke
				(width 0.1)
				(type default)
			)
			(layer "B.Fab")
		)
		(fp_line
			(start 0.299974 0.150114)
			(end 0.299974 -0.150114)
			(stroke
				(width 0.1)
				(type default)
			)
			(layer "B.Fab")
		)
		(pad "1" smd rect
			(at 0.2667 0 180)
			(size 0.3048 0.381)
			(layers "B.Cu" "B.Mask" "B.Paste")
			(net "P0V9_CPU0_RT3_2A")
		)
		(pad "2" smd rect
			(at -0.2667 0 180)
			(size 0.3048 0.381)
			(layers "B.Cu" "B.Mask" "B.Paste")
			(net "GND")
		)
	)
)
